#ISCELL
  mstr_misc dns *
  *
#ISCELL
  mstr_symbols cad_note *
  *
#ISCELL
  mstr_symbols design_note *
  *
#ISCELL
  mstr_symbols intel_corp_bpage *
  *
#ISCELL
  mstr_standard offpage *
  page238_i1
#ISCELL
  mstr_symbols gnd *
  page238_i13
#CELL
  mstr_discrete res *
  page238_i14
#ISCELL
  mstr_symbols gnd *
  page238_i15
#CELL
  mstr_discrete cap *
  page238_i19
#ISCELL
  mstr_symbols gnd *
  page238_i20
#CELL
  mstr_discrete res *
  page238_i21
#ISCELL
  mstr_symbols p3v3_stby *
  page238_i22
#CELL
  mstr_discrete cap *
  page238_i23
#ISCELL
  mstr_standard offpage *
  page238_i25
#ISCELL
  mstr_symbols gnd *
  page238_i27
#ISCELL
  mstr_symbols gnd *
  page238_i3
#CELL
  mstr_discrete cap *
  page238_i30
#CELL
  mstr_discrete cap *
  page238_i39
#ISCELL
  mstr_symbols gnd *
  page238_i4
#CELL
  mstr_vreg rt9059 *
  page238_i40
#CELL
  mstr_discrete res *
  page238_i41
#ISCELL
  mstr_symbols p3v3_stby *
  page238_i42
#ISCELL
  w_power w_vcc_circle *
  page238_i43
#ISCELL
  mstr_symbols p3v3_stby *
  page238_i44
#CELL
  w_hdl 4k42r2f-gp *
  page238_i45
#CELL
  mstr_discrete cap *
  page238_i46
#ISCELL
  mstr_symbols gnd *
  page238_i47
#CELL
  mstr_discrete cap *
  page238_i5
#CELL
  dev_discrete cap_a *
  page238_i50
#ISCELL
  mstr_symbols gnd *
  page238_i6
#CELL
  mstr_discrete cap *
  page238_i7
